# BASEBOARD_FAB2 (Tioga Pass) — schematic netlist excerpt (pin names and nets, part order shuffled) for the footprints in the layout excerpt that follows; sources: Cadence DE-HDL packaged netlist, KiCad conversion of Wiwynn_Tioga_Pass_MB.brd

R8G3  RES  2.26K 1.0% EMPTY  pkg 0402  page 159 : A = P3V3_STBY ; B = SMB_OCP_LAN_STBY_LVC3_SCL_R
C6G1  CAP  10UF 4V 20% X6S  pkg 0603LF  page 231 : A = PVPP_ABC ; B = GND
C7G30  CAP  1.0UF 16V 10% X6S  pkg 0402  page 216 : A = VR_FET_SW_P12V_STBY_PVDDQ_ABC ; B = GND

(kicad_pcb
	(version 20260206)
	(generator "pcbnew")
	(generator_version "10.0")
	(general
		(thickness 1.6)
		(legacy_teardrops no)
	)
	(paper "A4")
	(title_block
		(title "Wiwynn_Tioga_Pass_MB.brd")
		(comment 1 "Tioga Pass / footprints 739-741 of 4770")
	)
	(layers
		(0 "F.Cu" signal "TOP")
		(4 "In1.Cu" signal "L2GND")
		(6 "In2.Cu" signal "L3")
		(8 "In3.Cu" signal "L4GND")
		(10 "In4.Cu" signal "L5")
		(12 "In5.Cu" signal "L6GND")
		(14 "In6.Cu" signal "L7VCC")
		(16 "In7.Cu" signal "L8VCC")
		(18 "In8.Cu" signal "L9GND")
		(20 "In9.Cu" signal "L10")
		(22 "In10.Cu" signal "L11GND")
		(24 "In11.Cu" signal "L12")
		(26 "In12.Cu" signal "L13GND")
		(2 "B.Cu" signal "BOTTOM")
		(9 "F.Adhes" user "F.Adhesive")
		(11 "B.Adhes" user "B.Adhesive")
		(13 "F.Paste" user "Package Geometry/Pastemask Top")
		(15 "B.Paste" user "Package Geometry/Pastemask Bottom")
		(5 "F.SilkS" user "Ref Des/Silkscreen Top")
		(7 "B.SilkS" user "Ref Des/Silkscreen Bottom")
		(1 "F.Mask" user "Board Geometry/Soldermask Top")
		(3 "B.Mask" user "Board Geometry/Soldermask Bottom")
		(17 "Dwgs.User" user "User.Drawings")
		(19 "Cmts.User" user "User.Comments")
		(21 "Eco1.User" user "User.Eco1")
		(23 "Eco2.User" user "User.Eco2")
		(25 "Edge.Cuts" user "Board Geometry/Outline")
		(27 "Margin" user)
		(31 "F.CrtYd" user "Package Geometry/Place Bound Top")
		(29 "B.CrtYd" user "Package Geometry/Place Bound Bottom")
		(35 "F.Fab" user "Ref Des/Assembly Top")
		(33 "B.Fab" user "Ref Des/Assembly Bottom")
	)
	(footprint ""
		(layer "F.Cu")
		(at 398.874996 -36.565586 90)
		(property "Reference" "R8G3"
			(at 0 0 90)
			(layer "F.SilkS")
			(hide yes)
			(effects
				(font
					(size 1.27 1.27)
				)
			)
		)
		(property "Value" ""
			(at 0 0 90)
			(layer "F.Fab")
			(effects
				(font
					(size 1.27 1.27)
				)
			)
		)
		(duplicate_pad_numbers_are_jumpers no)
		(fp_poly
			(pts
				(xy -0.2794 -0.1016) (xy 0.2794 -0.1016) (xy 0.2794 0.9906) (xy -0.2794 0.9906)
			)
			(stroke
				(width 0)
				(type default)
			)
			(fill no)
			(layer "F.CrtYd")
		)
		(fp_line
			(start 0.2794 -0.1016)
			(end -0.2794 -0.1016)
			(stroke
				(width 0.1)
				(type default)
			)
			(layer "F.Fab")
		)
		(fp_line
			(start -0.2794 -0.1016)
			(end -0.2794 0.9906)
			(stroke
				(width 0.1)
				(type default)
			)
			(layer "F.Fab")
		)
		(fp_line
			(start 0.2794 0.9906)
			(end 0.2794 -0.1016)
			(stroke
				(width 0.1)
				(type default)
			)
			(layer "F.Fab")
		)
		(fp_line
			(start -0.2794 0.9906)
			(end 0.2794 0.9906)
			(stroke
				(width 0.1)
				(type default)
			)
			(layer "F.Fab")
		)
		(pad "1" smd rect
			(at 0 0 90)
			(size 0.508 0.508)
			(layers "F.Cu" "F.Mask" "F.Paste")
			(net "P3V3_STBY")
		)
		(pad "2" smd rect
			(at 0 0.889 90)
			(size 0.508 0.508)
			(layers "F.Cu" "F.Mask" "F.Paste")
			(net "SMB_OCP_LAN_STBY_LVC3_SCL_R")
		)
		(zone
			(layer "F.Cu")
			(hatch none 0.5)
			(connect_pads
				(clearance 0)
			)
			(min_thickness 0.25)
			(keepout
				(tracks allowed)
				(vias not_allowed)
				(pads allowed)
				(copperpour not_allowed)
				(footprints allowed)
			)
			(placement
				(enabled no)
				(sheetname "")
			)
			(fill
				(thermal_gap 0.5)
				(thermal_bridge_width 0.5)
				(island_removal_mode 0)
			)
			(polygon
				(pts
					(xy 399.128996 -36.311586) (xy 399.128996 -36.819586) (xy 399.509996 -36.819586) (xy 399.509996 -36.311586)
				)
			)
		)
		(zone
			(layer "F.Cu")
			(hatch none 0.5)
			(connect_pads
				(clearance 0)
			)
			(min_thickness 0.25)
			(keepout
				(tracks not_allowed)
				(vias allowed)
				(pads allowed)
				(copperpour not_allowed)
				(footprints allowed)
			)
			(placement
				(enabled no)
				(sheetname "")
			)
			(fill
				(thermal_gap 0.5)
				(thermal_bridge_width 0.5)
				(island_removal_mode 0)
			)
			(polygon
				(pts
					(xy 399.509996 -36.311586) (xy 399.509996 -36.819586) (xy 399.128996 -36.819586) (xy 399.128996 -36.311586)
				)
			)
		)
	)
	(footprint ""
		(layer "F.Cu")
		(at 350.05518 -3.146552)
		(property "Reference" "C7G30"
			(at 0 0 0)
			(layer "F.SilkS")
			(hide yes)
			(effects
				(font
					(size 1.27 1.27)
				)
			)
		)
		(property "Value" ""
			(at 0 0 0)
			(layer "F.Fab")
			(effects
				(font
					(size 1.27 1.27)
				)
			)
		)
		(duplicate_pad_numbers_are_jumpers no)
		(fp_poly
			(pts
				(xy 0.3048 -0.1016) (xy 0.3048 0.9906) (xy -0.3048 0.9906) (xy -0.3048 -0.1016)
			)
			(stroke
				(width 0)
				(type default)
			)
			(fill no)
			(layer "F.CrtYd")
		)
		(fp_line
			(start -0.3048 -0.1016)
			(end -0.3048 0.9906)
			(stroke
				(width 0.1)
				(type default)
			)
			(layer "F.Fab")
		)
		(fp_line
			(start -0.3048 0.9906)
			(end 0.3048 0.9906)
			(stroke
				(width 0.1)
				(type default)
			)
			(layer "F.Fab")
		)
		(fp_line
			(start 0.3048 -0.1016)
			(end -0.3048 -0.1016)
			(stroke
				(width 0.1)
				(type default)
			)
			(layer "F.Fab")
		)
		(fp_line
			(start 0.3048 0.9906)
			(end 0.3048 -0.1016)
			(stroke
				(width 0.1)
				(type default)
			)
			(layer "F.Fab")
		)
		(pad "1" smd rect
			(at 0 0)
			(size 0.508 0.508)
			(layers "F.Cu" "F.Mask" "F.Paste")
			(net "VR_FET_SW_P12V_STBY_PVDDQ_ABC")
		)
		(pad "2" smd rect
			(at 0 0.889)
			(size 0.508 0.508)
			(layers "F.Cu" "F.Mask" "F.Paste")
			(net "GND")
		)
		(zone
			(layer "F.Cu")
			(hatch none 0.5)
			(connect_pads
				(clearance 0)
			)
			(min_thickness 0.25)
			(keepout
				(tracks allowed)
				(vias not_allowed)
				(pads allowed)
				(copperpour not_allowed)
				(footprints allowed)
			)
			(placement
				(enabled no)
				(sheetname "")
			)
			(fill
				(thermal_gap 0.5)
				(thermal_bridge_width 0.5)
				(island_removal_mode 0)
			)
			(polygon
				(pts
					(xy 349.80118 -2.892552) (xy 350.30918 -2.892552) (xy 350.30918 -2.511552) (xy 349.80118 -2.511552)
				)
			)
		)
		(zone
			(layer "F.Cu")
			(hatch none 0.5)
			(connect_pads
				(clearance 0)
			)
			(min_thickness 0.25)
			(keepout
				(tracks not_allowed)
				(vias allowed)
				(pads allowed)
				(copperpour not_allowed)
				(footprints allowed)
			)
			(placement
				(enabled no)
				(sheetname "")
			)
			(fill
				(thermal_gap 0.5)
				(thermal_bridge_width 0.5)
				(island_removal_mode 0)
			)
			(polygon
				(pts
					(xy 349.80118 -2.511552) (xy 350.30918 -2.511552) (xy 350.30918 -2.892552) (xy 349.80118 -2.892552)
				)
			)
		)
	)
	(footprint ""
		(layer "F.Cu")
		(at 318.543432 -12.954 -90)
		(property "Reference" "C6G1"
			(at 0 0 270)
			(layer "F.SilkS")
			(hide yes)
			(effects
				(font
					(size 1.27 1.27)
				)
			)
		)
		(property "Value" ""
			(at 0 0 270)
			(layer "F.Fab")
			(effects
				(font
					(size 1.27 1.27)
				)
			)
		)
		(duplicate_pad_numbers_are_jumpers no)
		(fp_poly
			(pts
				(xy -0.4953 -0.2032) (xy 0.4953 -0.2032) (xy 0.4953 1.6002) (xy -0.4953 1.6002)
			)
			(stroke
				(width 0)
				(type default)
			)
			(fill no)
			(layer "F.CrtYd")
		)
		(fp_line
			(start -0.4953 1.6002)
			(end -0.4953 -0.2032)
			(stroke
				(width 0.1)
				(type default)
			)
			(layer "F.Fab")
		)
		(fp_line
			(start 0.4953 1.6002)
			(end -0.4953 1.6002)
			(stroke
				(width 0.1)
				(type default)
			)
			(layer "F.Fab")
		)
		(fp_line
			(start -0.4953 -0.2032)
			(end 0.4953 -0.2032)
			(stroke
				(width 0.1)
				(type default)
			)
			(layer "F.Fab")
		)
		(fp_line
			(start 0.4953 -0.2032)
			(end 0.4953 1.6002)
			(stroke
				(width 0.1)
				(type default)
			)
			(layer "F.Fab")
		)
		(pad "1" smd rect
			(at 0 0 270)
			(size 0.762 0.889)
			(layers "F.Cu" "F.Mask" "F.Paste")
			(net "PVPP_ABC")
		)
		(pad "2" smd rect
			(at 0 1.397 270)
			(size 0.762 0.889)
			(layers "F.Cu" "F.Mask" "F.Paste")
			(net "GND")
		)
		(zone
			(layer "F.Cu")
			(hatch none 0.5)
			(connect_pads
				(clearance 0)
			)
			(min_thickness 0.25)
			(keepout
				(tracks not_allowed)
				(vias allowed)
				(pads allowed)
				(copperpour not_allowed)
				(footprints allowed)
			)
			(placement
				(enabled no)
				(sheetname "")
			)
			(fill
				(thermal_gap 0.5)
				(thermal_bridge_width 0.5)
				(island_removal_mode 0)
			)
			(polygon
				(pts
					(xy 318.098932 -13.335) (xy 318.098932 -12.573) (xy 317.590932 -12.573) (xy 317.590932 -13.335)
				)
			)
		)
	)
)
